(kicad_pcb
	(version 20260206)
	(generator "pcbnew")
	(generator_version "10.0")
	(general
		(thickness 1.6)
		(legacy_teardrops no)
	)
	(paper "A4")
	(title_block
		(title "04192023_DAF0TMB3IC0_F0TG_MB_C_brd_V02_OCP.brd")
		(comment 1 "Grand Teton / footprints 8203-8209 of 8354")
	)
	(layers
		(0 "F.Cu" signal "TOP")
		(4 "In1.Cu" signal "GND")
		(6 "In2.Cu" signal "IN1")
		(8 "In3.Cu" signal "GND1")
		(10 "In4.Cu" signal "IN2")
		(12 "In5.Cu" signal "GND2")
		(14 "In6.Cu" signal "IN3")
		(16 "In7.Cu" signal "GND3")
		(18 "In8.Cu" signal "VCC")
		(20 "In9.Cu" signal "VCC1")
		(22 "In10.Cu" signal "GND4")
		(24 "In11.Cu" signal "IN4")
		(26 "In12.Cu" signal "GND5")
		(28 "In13.Cu" signal "IN5")
		(30 "In14.Cu" signal "GND6")
		(32 "In15.Cu" signal "IN6")
		(34 "In16.Cu" signal "GND7")
		(2 "B.Cu" signal "BOTTOM")
		(9 "F.Adhes" user "F.Adhesive")
		(11 "B.Adhes" user "B.Adhesive")
		(13 "F.Paste" user "Package Geometry/Pastemask Top")
		(15 "B.Paste" user "Package Geometry/Pastemask Bottom")
		(5 "F.SilkS" user "Ref Des/Silkscreen Top")
		(7 "B.SilkS" user "Ref Des/Silkscreen Bottom")
		(1 "F.Mask" user "Board Geometry/Soldermask Top")
		(3 "B.Mask" user "Board Geometry/Soldermask Bottom")
		(17 "Dwgs.User" user "User.Drawings")
		(19 "Cmts.User" user "User.Comments")
		(21 "Eco1.User" user "User.Eco1")
		(23 "Eco2.User" user "User.Eco2")
		(25 "Edge.Cuts" user "Board Geometry/Outline")
		(27 "Margin" user)
		(31 "F.CrtYd" user "Package Geometry/Place Bound Top")
		(29 "B.CrtYd" user "Package Geometry/Place Bound Bottom")
		(35 "F.Fab" user "Ref Des/Assembly Top")
		(33 "B.Fab" user "Ref Des/Assembly Bottom")
	)
	(footprint ""
		(layer "B.Cu")
		(at 459.339188 -389.132064 -90)
		(property "Reference" "PC6566_1"
			(at 0 0 90)
			(layer "B.SilkS")
			(hide yes)
			(effects
				(font
					(size 1.27 1.27)
				)
				(justify mirror)
			)
		)
		(property "Value" ""
			(at 0 0 90)
			(layer "B.Fab")
			(effects
				(font
					(size 1.27 1.27)
				)
				(justify mirror)
			)
		)
		(duplicate_pad_numbers_are_jumpers no)
		(fp_line
			(start -1.524 0.762)
			(end 1.524 0.762)
			(stroke
				(width 0.1524)
				(type default)
			)
			(layer "B.SilkS")
		)
		(fp_line
			(start 1.524 0.762)
			(end 1.524 -0.762)
			(stroke
				(width 0.1524)
				(type default)
			)
			(layer "B.SilkS")
		)
		(fp_line
			(start -1.524 -0.762)
			(end -1.524 0.762)
			(stroke
				(width 0.1524)
				(type default)
			)
			(layer "B.SilkS")
		)
		(fp_line
			(start 1.524 -0.762)
			(end -1.524 -0.762)
			(stroke
				(width 0.1524)
				(type default)
			)
			(layer "B.SilkS")
		)
		(fp_line
			(start -1.1049 0.724916)
			(end -1.1049 -0.724916)
			(stroke
				(width 0.1)
				(type default)
			)
			(layer "B.Fab")
		)
		(fp_line
			(start 1.1049 0.724916)
			(end -1.1049 0.724916)
			(stroke
				(width 0.1)
				(type default)
			)
			(layer "B.Fab")
		)
		(fp_line
			(start -1.1049 -0.724916)
			(end 1.1049 -0.724916)
			(stroke
				(width 0.1)
				(type default)
			)
			(layer "B.Fab")
		)
		(fp_line
			(start 1.1049 -0.724916)
			(end 1.1049 0.724916)
			(stroke
				(width 0.1)
				(type default)
			)
			(layer "B.Fab")
		)
		(pad "1" smd rect
			(at 0.889 0 270)
			(size 1.016 1.27)
			(layers "B.Cu" "B.Mask" "B.Paste")
			(net "P0V9_CPU0_RT_2D")
		)
		(pad "2" smd rect
			(at -0.889 0 270)
			(size 1.016 1.27)
			(layers "B.Cu" "B.Mask" "B.Paste")
			(net "GND")
		)
	)
	(footprint ""
		(layer "B.Cu")
		(at 371.650006 -178.994816 90)
		(property "Reference" "PC484_2"
			(at 0 0 90)
			(layer "B.SilkS")
			(hide yes)
			(effects
				(font
					(size 1.27 1.27)
				)
				(justify mirror)
			)
		)
		(property "Value" ""
			(at 0 0 90)
			(layer "B.Fab")
			(effects
				(font
					(size 1.27 1.27)
				)
				(justify mirror)
			)
		)
		(duplicate_pad_numbers_are_jumpers no)
		(fp_line
			(start 1.524 -0.762)
			(end -1.524 -0.762)
			(stroke
				(width 0.1524)
				(type default)
			)
			(layer "B.SilkS")
		)
		(fp_line
			(start -1.524 -0.762)
			(end -1.524 0.762)
			(stroke
				(width 0.1524)
				(type default)
			)
			(layer "B.SilkS")
		)
		(fp_line
			(start 1.524 0.762)
			(end 1.524 -0.762)
			(stroke
				(width 0.1524)
				(type default)
			)
			(layer "B.SilkS")
		)
		(fp_line
			(start -1.524 0.762)
			(end 1.524 0.762)
			(stroke
				(width 0.1524)
				(type default)
			)
			(layer "B.SilkS")
		)
		(fp_line
			(start 1.1049 -0.724916)
			(end 1.1049 0.724916)
			(stroke
				(width 0.1)
				(type default)
			)
			(layer "B.Fab")
		)
		(fp_line
			(start -1.1049 -0.724916)
			(end 1.1049 -0.724916)
			(stroke
				(width 0.1)
				(type default)
			)
			(layer "B.Fab")
		)
		(fp_line
			(start 1.1049 0.724916)
			(end -1.1049 0.724916)
			(stroke
				(width 0.1)
				(type default)
			)
			(layer "B.Fab")
		)
		(fp_line
			(start -1.1049 0.724916)
			(end -1.1049 -0.724916)
			(stroke
				(width 0.1)
				(type default)
			)
			(layer "B.Fab")
		)
		(pad "1" smd rect
			(at 0.889 0 90)
			(size 1.016 1.27)
			(layers "B.Cu" "B.Mask" "B.Paste")
			(net "SW_P12V_AUX_PVDDCR_CPU0_P0_FLT")
		)
		(pad "2" smd rect
			(at -0.889 0 90)
			(size 1.016 1.27)
			(layers "B.Cu" "B.Mask" "B.Paste")
			(net "GND")
		)
	)
	(footprint ""
		(layer "B.Cu")
		(at 371.678454 -395.148562 90)
		(property "Reference" "C1031"
			(at 0 0 90)
			(layer "B.SilkS")
			(hide yes)
			(effects
				(font
					(size 1.27 1.27)
				)
				(justify mirror)
			)
		)
		(property "Value" ""
			(at 0 0 90)
			(layer "B.Fab")
			(effects
				(font
					(size 1.27 1.27)
				)
				(justify mirror)
			)
		)
		(duplicate_pad_numbers_are_jumpers no)
		(fp_line
			(start 0.299974 -0.150114)
			(end -0.299974 -0.150114)
			(stroke
				(width 0.1)
				(type default)
			)
			(layer "B.Fab")
		)
		(fp_line
			(start -0.299974 -0.150114)
			(end -0.299974 0.150114)
			(stroke
				(width 0.1)
				(type default)
			)
			(layer "B.Fab")
		)
		(fp_line
			(start 0.299974 0.150114)
			(end 0.299974 -0.150114)
			(stroke
				(width 0.1)
				(type default)
			)
			(layer "B.Fab")
		)
		(fp_line
			(start -0.299974 0.150114)
			(end 0.299974 0.150114)
			(stroke
				(width 0.1)
				(type default)
			)
			(layer "B.Fab")
		)
		(pad "1" smd rect
			(at 0.2667 0 270)
			(size 0.3048 0.381)
			(layers "B.Cu" "B.Mask" "B.Paste")
			(net "P0V9_CPU0_RT3_2A")
		)
		(pad "2" smd rect
			(at -0.2667 0 270)
			(size 0.3048 0.381)
			(layers "B.Cu" "B.Mask" "B.Paste")
			(net "GND")
		)
	)
	(footprint ""
		(layer "B.Cu")
		(at 363.010958 -246.376952 180)
		(property "Reference" "C2185"
			(at 0 0 0)
			(layer "B.SilkS")
			(hide yes)
			(effects
				(font
					(size 1.27 1.27)
				)
				(justify mirror)
			)
		)
		(property "Value" ""
			(at 0 0 0)
			(layer "B.Fab")
			(effects
				(font
					(size 1.27 1.27)
				)
				(justify mirror)
			)
		)
		(duplicate_pad_numbers_are_jumpers no)
		(fp_line
			(start 0.7874 0.4064)
			(end 0.7874 -0.4064)
			(stroke
				(width 0.1524)
				(type default)
			)
			(layer "B.SilkS")
		)
		(fp_line
			(start 0.7874 -0.4064)
			(end -0.7874 -0.4064)
			(stroke
				(width 0.1524)
				(type default)
			)
			(layer "B.SilkS")
		)
		(fp_line
			(start -0.7874 0.4064)
			(end 0.7874 0.4064)
			(stroke
				(width 0.1524)
				(type default)
			)
			(layer "B.SilkS")
		)
		(fp_line
			(start -0.7874 -0.4064)
			(end -0.7874 0.4064)
			(stroke
				(width 0.1524)
				(type default)
			)
			(layer "B.SilkS")
		)
		(fp_line
			(start 0.67945 0.3048)
			(end 0.67945 -0.305054)
			(stroke
				(width 0.1)
				(type default)
			)
			(layer "B.Fab")
		)
		(fp_line
			(start 0.67945 -0.305054)
			(end 0.12065 -0.305054)
			(stroke
				(width 0.1)
				(type default)
			)
			(layer "B.Fab")
		)
		(fp_line
			(start 0.12065 0.3048)
			(end 0.67945 0.3048)
			(stroke
				(width 0.1)
				(type default)
			)
			(layer "B.Fab")
		)
		(fp_line
			(start 0.12065 0.2794)
			(end 0.12065 0.3048)
			(stroke
				(width 0.1)
				(type default)
			)
			(layer "B.Fab")
		)
		(fp_line
			(start 0.12065 -0.2794)
			(end -0.12065 -0.2794)
			(stroke
				(width 0.1)
				(type default)
			)
			(layer "B.Fab")
		)
		(fp_line
			(start 0.12065 -0.305054)
			(end 0.12065 -0.2794)
			(stroke
				(width 0.1)
				(type default)
			)
			(layer "B.Fab")
		)
		(fp_line
			(start -0.120396 0.3048)
			(end -0.120396 0.2794)
			(stroke
				(width 0.1)
				(type default)
			)
			(layer "B.Fab")
		)
		(fp_line
			(start -0.120396 0.2794)
			(end 0.12065 0.2794)
			(stroke
				(width 0.1)
				(type default)
			)
			(layer "B.Fab")
		)
		(fp_line
			(start -0.12065 -0.2794)
			(end -0.12065 -0.3048)
			(stroke
				(width 0.1)
				(type default)
			)
			(layer "B.Fab")
		)
		(fp_line
			(start -0.12065 -0.3048)
			(end -0.67945 -0.3048)
			(stroke
				(width 0.1)
				(type default)
			)
			(layer "B.Fab")
		)
		(fp_line
			(start -0.67945 0.3048)
			(end -0.120396 0.3048)
			(stroke
				(width 0.1)
				(type default)
			)
			(layer "B.Fab")
		)
		(fp_line
			(start -0.67945 -0.3048)
			(end -0.67945 0.3048)
			(stroke
				(width 0.1)
				(type default)
			)
			(layer "B.Fab")
		)
		(pad "1" smd circle
			(at 0.40005 0)
			(size 0 0)
			(layers "B.Cu" "B.Mask" "B.Paste")
			(net "PVDDCR_CPU0_P0")
		)
		(pad "2" smd circle
			(at -0.40005 0)
			(size 0 0)
			(layers "B.Cu" "B.Mask" "B.Paste")
			(net "GND")
		)
	)
	(footprint ""
		(layer "B.Cu")
		(at 299.06849 -194.893946 180)
		(property "Reference" "R1569"
			(at 0 0 0)
			(layer "B.SilkS")
			(hide yes)
			(effects
				(font
					(size 1.27 1.27)
				)
				(justify mirror)
			)
		)
		(property "Value" ""
			(at 0 0 0)
			(layer "B.Fab")
			(effects
				(font
					(size 1.27 1.27)
				)
				(justify mirror)
			)
		)
		(duplicate_pad_numbers_are_jumpers no)
		(fp_line
			(start 0.7874 0.4064)
			(end 0.7874 -0.4064)
			(stroke
				(width 0.1524)
				(type default)
			)
			(layer "B.SilkS")
		)
		(fp_line
			(start 0.7874 -0.4064)
			(end -0.7874 -0.4064)
			(stroke
				(width 0.1524)
				(type default)
			)
			(layer "B.SilkS")
		)
		(fp_line
			(start -0.7874 0.4064)
			(end 0.7874 0.4064)
			(stroke
				(width 0.1524)
				(type default)
			)
			(layer "B.SilkS")
		)
		(fp_line
			(start -0.7874 -0.4064)
			(end -0.7874 0.4064)
			(stroke
				(width 0.1524)
				(type default)
			)
			(layer "B.SilkS")
		)
		(fp_line
			(start 0.67945 0.3048)
			(end 0.67945 -0.305054)
			(stroke
				(width 0.1)
				(type default)
			)
			(layer "B.Fab")
		)
		(fp_line
			(start 0.67945 -0.305054)
			(end 0.12065 -0.305054)
			(stroke
				(width 0.1)
				(type default)
			)
			(layer "B.Fab")
		)
		(fp_line
			(start 0.12065 0.3048)
			(end 0.67945 0.3048)
			(stroke
				(width 0.1)
				(type default)
			)
			(layer "B.Fab")
		)
		(fp_line
			(start 0.12065 0.2794)
			(end 0.12065 0.3048)
			(stroke
				(width 0.1)
				(type default)
			)
			(layer "B.Fab")
		)
		(fp_line
			(start 0.12065 -0.2794)
			(end -0.12065 -0.2794)
			(stroke
				(width 0.1)
				(type default)
			)
			(layer "B.Fab")
		)
		(fp_line
			(start 0.12065 -0.305054)
			(end 0.12065 -0.2794)
			(stroke
				(width 0.1)
				(type default)
			)
			(layer "B.Fab")
		)
		(fp_line
			(start -0.120396 0.3048)
			(end -0.120396 0.2794)
			(stroke
				(width 0.1)
				(type default)
			)
			(layer "B.Fab")
		)
		(fp_line
			(start -0.120396 0.2794)
			(end 0.12065 0.2794)
			(stroke
				(width 0.1)
				(type default)
			)
			(layer "B.Fab")
		)
		(fp_line
			(start -0.12065 -0.2794)
			(end -0.12065 -0.3048)
			(stroke
				(width 0.1)
				(type default)
			)
			(layer "B.Fab")
		)
		(fp_line
			(start -0.12065 -0.3048)
			(end -0.67945 -0.3048)
			(stroke
				(width 0.1)
				(type default)
			)
			(layer "B.Fab")
		)
		(fp_line
			(start -0.67945 0.3048)
			(end -0.120396 0.3048)
			(stroke
				(width 0.1)
				(type default)
			)
			(layer "B.Fab")
		)
		(fp_line
			(start -0.67945 -0.3048)
			(end -0.67945 0.3048)
			(stroke
				(width 0.1)
				(type default)
			)
			(layer "B.Fab")
		)
		(pad "1" smd circle
			(at 0.40005 0)
			(size 0 0)
			(layers "B.Cu" "B.Mask" "B.Paste")
			(net "I3C_SPD_DDRAF_CPU0_SCL")
		)
		(pad "2" smd circle
			(at -0.40005 0)
			(size 0 0)
			(layers "B.Cu" "B.Mask" "B.Paste")
			(net "I3C_SPD_DDRB_CPU0_SCL")
		)
	)
	(footprint ""
		(layer "B.Cu")
		(at 239.649 -227.203 180)
		(property "Reference" "R790"
			(at 0 0 0)
			(layer "B.SilkS")
			(hide yes)
			(effects
				(font
					(size 1.27 1.27)
				)
				(justify mirror)
			)
		)
		(property "Value" ""
			(at 0 0 0)
			(layer "B.Fab")
			(effects
				(font
					(size 1.27 1.27)
				)
				(justify mirror)
			)
		)
		(duplicate_pad_numbers_are_jumpers no)
		(fp_line
			(start 0.7874 0.4064)
			(end 0.7874 -0.4064)
			(stroke
				(width 0.1524)
				(type default)
			)
			(layer "B.SilkS")
		)
		(fp_line
			(start 0.7874 -0.4064)
			(end -0.7874 -0.4064)
			(stroke
				(width 0.1524)
				(type default)
			)
			(layer "B.SilkS")
		)
		(fp_line
			(start -0.7874 0.4064)
			(end 0.7874 0.4064)
			(stroke
				(width 0.1524)
				(type default)
			)
			(layer "B.SilkS")
		)
		(fp_line
			(start -0.7874 -0.4064)
			(end -0.7874 0.4064)
			(stroke
				(width 0.1524)
				(type default)
			)
			(layer "B.SilkS")
		)
		(fp_line
			(start 0.67945 0.3048)
			(end 0.67945 -0.305054)
			(stroke
				(width 0.1)
				(type default)
			)
			(layer "B.Fab")
		)
		(fp_line
			(start 0.67945 -0.305054)
			(end 0.12065 -0.305054)
			(stroke
				(width 0.1)
				(type default)
			)
			(layer "B.Fab")
		)
		(fp_line
			(start 0.12065 0.3048)
			(end 0.67945 0.3048)
			(stroke
				(width 0.1)
				(type default)
			)
			(layer "B.Fab")
		)
		(fp_line
			(start 0.12065 0.2794)
			(end 0.12065 0.3048)
			(stroke
				(width 0.1)
				(type default)
			)
			(layer "B.Fab")
		)
		(fp_line
			(start 0.12065 -0.2794)
			(end -0.12065 -0.2794)
			(stroke
				(width 0.1)
				(type default)
			)
			(layer "B.Fab")
		)
		(fp_line
			(start 0.12065 -0.305054)
			(end 0.12065 -0.2794)
			(stroke
				(width 0.1)
				(type default)
			)
			(layer "B.Fab")
		)
		(fp_line
			(start -0.120396 0.3048)
			(end -0.120396 0.2794)
			(stroke
				(width 0.1)
				(type default)
			)
			(layer "B.Fab")
		)
		(fp_line
			(start -0.120396 0.2794)
			(end 0.12065 0.2794)
			(stroke
				(width 0.1)
				(type default)
			)
			(layer "B.Fab")
		)
		(fp_line
			(start -0.12065 -0.2794)
			(end -0.12065 -0.3048)
			(stroke
				(width 0.1)
				(type default)
			)
			(layer "B.Fab")
		)
		(fp_line
			(start -0.12065 -0.3048)
			(end -0.67945 -0.3048)
			(stroke
				(width 0.1)
				(type default)
			)
			(layer "B.Fab")
		)
		(fp_line
			(start -0.67945 0.3048)
			(end -0.120396 0.3048)
			(stroke
				(width 0.1)
				(type default)
			)
			(layer "B.Fab")
		)
		(fp_line
			(start -0.67945 -0.3048)
			(end -0.67945 0.3048)
			(stroke
				(width 0.1)
				(type default)
			)
			(layer "B.Fab")
		)
		(pad "1" smd circle
			(at 0.40005 0)
			(size 0 0)
			(layers "B.Cu" "B.Mask" "B.Paste")
			(net "SMB_CPU0_CPU1_APML_BUF1_SDA")
		)
		(pad "2" smd circle
			(at -0.40005 0)
			(size 0 0)
			(layers "B.Cu" "B.Mask" "B.Paste")
			(net "SMB_CPU0_CPU1_APML_BUF1_SDA_R1")
		)
	)
	(footprint ""
		(layer "B.Cu")
		(at 167.936418 -350.732344)
		(property "Reference" "PR388"
			(at 0 0 0)
			(layer "B.SilkS")
			(hide yes)
			(effects
				(font
					(size 1.27 1.27)
				)
				(justify mirror)
			)
		)
		(property "Value" ""
			(at 0 0 0)
			(layer "B.Fab")
			(effects
				(font
					(size 1.27 1.27)
				)
				(justify mirror)
			)
		)
		(duplicate_pad_numbers_are_jumpers no)
		(fp_line
			(start -0.7874 -0.4064)
			(end -0.7874 0.4064)
			(stroke
				(width 0.1524)
				(type default)
			)
			(layer "B.SilkS")
		)
		(fp_line
			(start -0.7874 0.4064)
			(end 0.7874 0.4064)
			(stroke
				(width 0.1524)
				(type default)
			)
			(layer "B.SilkS")
		)
		(fp_line
			(start 0.7874 -0.4064)
			(end -0.7874 -0.4064)
			(stroke
				(width 0.1524)
				(type default)
			)
			(layer "B.SilkS")
		)
		(fp_line
			(start 0.7874 0.4064)
			(end 0.7874 -0.4064)
			(stroke
				(width 0.1524)
				(type default)
			)
			(layer "B.SilkS")
		)
		(fp_line
			(start -0.67945 -0.3048)
			(end -0.67945 0.3048)
			(stroke
				(width 0.1)
				(type default)
			)
			(layer "B.Fab")
		)
		(fp_line
			(start -0.67945 0.3048)
			(end -0.120396 0.3048)
			(stroke
				(width 0.1)
				(type default)
			)
			(layer "B.Fab")
		)
		(fp_line
			(start -0.12065 -0.3048)
			(end -0.67945 -0.3048)
			(stroke
				(width 0.1)
				(type default)
			)
			(layer "B.Fab")
		)
		(fp_line
			(start -0.12065 -0.2794)
			(end -0.12065 -0.3048)
			(stroke
				(width 0.1)
				(type default)
			)
			(layer "B.Fab")
		)
		(fp_line
			(start -0.120396 0.2794)
			(end 0.12065 0.2794)
			(stroke
				(width 0.1)
				(type default)
			)
			(layer "B.Fab")
		)
		(fp_line
			(start -0.120396 0.3048)
			(end -0.120396 0.2794)
			(stroke
				(width 0.1)
				(type default)
			)
			(layer "B.Fab")
		)
		(fp_line
			(start 0.12065 -0.305054)
			(end 0.12065 -0.2794)
			(stroke
				(width 0.1)
				(type default)
			)
			(layer "B.Fab")
		)
		(fp_line
			(start 0.12065 -0.2794)
			(end -0.12065 -0.2794)
			(stroke
				(width 0.1)
				(type default)
			)
			(layer "B.Fab")
		)
		(fp_line
			(start 0.12065 0.2794)
			(end 0.12065 0.3048)
			(stroke
				(width 0.1)
				(type default)
			)
			(layer "B.Fab")
		)
		(fp_line
			(start 0.12065 0.3048)
			(end 0.67945 0.3048)
			(stroke
				(width 0.1)
				(type default)
			)
			(layer "B.Fab")
		)
		(fp_line
			(start 0.67945 -0.305054)
			(end 0.12065 -0.305054)
			(stroke
				(width 0.1)
				(type default)
			)
			(layer "B.Fab")
		)
		(fp_line
			(start 0.67945 0.3048)
			(end 0.67945 -0.305054)
			(stroke
				(width 0.1)
				(type default)
			)
			(layer "B.Fab")
		)
		(pad "1" smd circle
			(at 0.40005 0 180)
			(size 0 0)
			(layers "B.Cu" "B.Mask" "B.Paste")
			(net "P12V_AUX")
		)
		(pad "2" smd circle
			(at -0.40005 0 180)
			(size 0 0)
			(layers "B.Cu" "B.Mask" "B.Paste")
			(net "PVDD11_S3_P1_VINSEN")
		)
	)
)
